(kicad_pcb
	(version 20241229)
	(generator "pcbnew")
	(generator_version "9.0")
	(general
		(thickness 1.599998)
		(legacy_teardrops no)
	)
	(paper "A4")
	(title_block
		(title "Artix - Datacenter Secure Control Module (DC-SCM)")
		(date "2024-11-06")
		(rev "1.1.3")
		(comment 9 "footprints 10-15 of 544")
	)
	(layers
		(0 "F.Cu" signal)
		(4 "In1.Cu" signal)
		(6 "In2.Cu" signal)
		(8 "In3.Cu" signal)
		(10 "In4.Cu" signal)
		(12 "In5.Cu" signal)
		(14 "In6.Cu" signal)
		(2 "B.Cu" signal)
		(9 "F.Adhes" user "F.Adhesive")
		(11 "B.Adhes" user "B.Adhesive")
		(13 "F.Paste" user)
		(15 "B.Paste" user)
		(5 "F.SilkS" user "F.Silkscreen")
		(7 "B.SilkS" user "B.Silkscreen")
		(1 "F.Mask" user)
		(3 "B.Mask" user)
		(17 "Dwgs.User" user "User.Drawings")
		(19 "Cmts.User" user "User.Comments")
		(21 "Eco1.User" user "User.Eco1")
		(23 "Eco2.User" user "User.Eco2")
		(25 "Edge.Cuts" user)
		(27 "Margin" user)
		(31 "F.CrtYd" user "F.Courtyard")
		(29 "B.CrtYd" user "B.Courtyard")
		(35 "F.Fab" user)
		(33 "B.Fab" user)
	)
	(footprint "antmicro-footprints:LED_0603_1608Metric_G"
		(layer "F.Cu")
		(at 138.575 157.875 -90)
		(descr "LED SMD 0603 Green")
		(tags "LED SMD 0603 Green")
		(property "Reference" "D1"
			(at -2.775 -0.425 90)
			(layer "F.SilkS")
			(effects
				(font
					(size 0.7 0.7)
					(thickness 0.15)
				)
				(justify right bottom)
			)
		)
		(property "Value" "LED_G_0603_KP-1608CGCK"
			(at 0 1.6 90)
			(layer "F.Fab")
			(effects
				(font
					(size 0.7 0.7)
					(thickness 0.15)
				)
				(justify right bottom)
			)
		)
		(property "Datasheet" "http://www.kingbright.com/attachments/file/psearch//000/00/00/KP-1608CGCK(Ver.23B).pdf"
			(at 0 0 270)
			(layer "F.Fab")
			(hide yes)
			(effects
				(font
					(size 1.27 1.27)
					(thickness 0.15)
				)
			)
		)
		(property "Description" "LED, Green, SMD, 0603, 20 mA, 2.1 V, 570 nm"
			(at 0 0 270)
			(layer "F.Fab")
			(hide yes)
			(effects
				(font
					(size 1.27 1.27)
					(thickness 0.15)
				)
			)
		)
		(property "Author" "Antmicro"
			(at -19.3 296.45 0)
			(layer "F.Fab")
			(hide yes)
			(effects
				(font
					(size 1 1)
					(thickness 0.15)
				)
			)
		)
		(property "Color" "Green"
			(at -19.3 296.45 0)
			(layer "F.Fab")
			(hide yes)
			(effects
				(font
					(size 1 1)
					(thickness 0.15)
				)
			)
		)
		(property "License" "Apache-2.0"
			(at -19.3 296.45 0)
			(layer "F.Fab")
			(hide yes)
			(effects
				(font
					(size 1 1)
					(thickness 0.15)
				)
			)
		)
		(property "MPN" "KP-1608CGCK"
			(at -19.3 296.45 0)
			(layer "F.Fab")
			(hide yes)
			(effects
				(font
					(size 1 1)
					(thickness 0.15)
				)
			)
		)
		(property "Manufacturer" "Kingbright"
			(at -19.3 296.45 0)
			(layer "F.Fab")
			(hide yes)
			(effects
				(font
					(size 1 1)
					(thickness 0.15)
				)
			)
		)
		(sheetname "/PCIe-connector/")
		(sheetfile "pcie-conn.kicad_sch")
		(attr smd)
		(fp_line
			(start 0.22 0.35)
			(end -0.22 0.35)
			(stroke
				(width 0.15)
				(type solid)
			)
			(layer "F.SilkS")
		)
		(fp_line
			(start -0.094672 0.201008)
			(end -0.094672 -0.198992)
			(stroke
				(width 0.1)
				(type solid)
			)
			(layer "F.SilkS")
		)
		(fp_line
			(start 0.105328 0.201008)
			(end -0.094672 0.001008)
			(stroke
				(width 0.1)
				(type solid)
			)
			(layer "F.SilkS")
		)
		(fp_line
			(start 0.105328 0.201008)
			(end 0.105328 -0.198992)
			(stroke
				(width 0.1)
				(type solid)
			)
			(layer "F.SilkS")
		)
		(fp_line
			(start -0.094672 0.001008)
			(end -0.24 0.001008)
			(stroke
				(width 0.1)
				(type solid)
			)
			(layer "F.SilkS")
		)
		(fp_line
			(start -0.094672 0.001008)
			(end 0.105328 -0.198992)
			(stroke
				(width 0.1)
				(type solid)
			)
			(layer "F.SilkS")
		)
		(fp_line
			(start 0.105328 0.001008)
			(end 0.24 0.001)
			(stroke
				(width 0.1)
				(type solid)
			)
			(layer "F.SilkS")
		)
		(fp_line
			(start -1.18 -0.319)
			(end -1.18 0.321)
			(stroke
				(width 0.15)
				(type solid)
			)
			(layer "F.SilkS")
		)
		(fp_line
			(start 0.22 -0.35)
			(end -0.22 -0.35)
			(stroke
				(width 0.15)
				(type solid)
			)
			(layer "F.SilkS")
		)
		(fp_rect
			(start 1.25 0.65)
			(end -1.25 -0.65)
			(stroke
				(width 0.05)
				(type solid)
			)
			(fill no)
			(layer "F.CrtYd")
		)
		(fp_line
			(start -0.199 0.2)
			(end -0.199 0.1)
			(stroke
				(width 0.15)
				(type solid)
			)
			(layer "F.Fab")
		)
		(fp_line
			(start 0.201 0.2)
			(end 0.201 0)
			(stroke
				(width 0.15)
				(type solid)
			)
			(layer "F.Fab")
		)
		(fp_line
			(start -0.199 0)
			(end -0.597 0)
			(stroke
				(width 0.15)
				(type solid)
			)
			(layer "F.Fab")
		)
		(fp_line
			(start -0.101 0)
			(end 0.201 0.2)
			(stroke
				(width 0.15)
				(type solid)
			)
			(layer "F.Fab")
		)
		(fp_line
			(start 0.201 0)
			(end 0.201 -0.202)
			(stroke
				(width 0.15)
				(type solid)
			)
			(layer "F.Fab")
		)
		(fp_line
			(start 0.599 0)
			(end 0.201 0)
			(stroke
				(width 0.15)
				(type solid)
			)
			(layer "F.Fab")
		)
		(fp_line
			(start -0.199 -0.202)
			(end -0.199 0.1)
			(stroke
				(width 0.15)
				(type solid)
			)
			(layer "F.Fab")
		)
		(fp_line
			(start 0.201 -0.202)
			(end -0.101 0)
			(stroke
				(width 0.15)
				(type solid)
			)
			(layer "F.Fab")
		)
		(fp_rect
			(start 0.848 0.4)
			(end -0.85 -0.402)
			(stroke
				(width 0.15)
				(type solid)
			)
			(fill no)
			(layer "F.Fab")
		)
		(pad "1" smd roundrect
			(at -0.7 0 90)
			(size 0.8 1)
			(layers "F.Cu" "F.Mask" "F.Paste")
			(roundrect_rratio 0.2)
			(net 527 "/PCIe-connector/NVME_LED")
			(pinfunction "C")
			(pintype "passive")
		)
		(pad "2" smd roundrect
			(at 0.7 0 90)
			(size 0.8 1)
			(layers "F.Cu" "F.Mask" "F.Paste")
			(roundrect_rratio 0.2)
			(net 112 "Net-(D1-A)")
			(pinfunction "A")
			(pintype "passive")
		)
	)
	(footprint "antmicro-footprints:R_0402_1005Metric"
		(layer "F.Cu")
		(at 122.5 154.21 -90)
		(descr "Resistor SMD 0402")
		(tags "resistor SMD 0402")
		(property "Reference" "R17"
			(at -2.92 -0.33 90)
			(layer "F.SilkS")
			(effects
				(font
					(size 0.7 0.7)
					(thickness 0.15)
				)
				(justify right bottom)
			)
		)
		(property "Value" "R_10k_0402"
			(at 0 1.4 90)
			(layer "F.Fab")
			(effects
				(font
					(size 0.7 0.7)
					(thickness 0.15)
				)
				(justify right bottom)
			)
		)
		(property "Datasheet" "https://www.bourns.com/docs/product-datasheets/cr.pdf"
			(at 0 0 270)
			(layer "F.Fab")
			(hide yes)
			(effects
				(font
					(size 1.27 1.27)
					(thickness 0.15)
				)
			)
		)
		(property "Description" "SMD Chip Resistor, 10 kohm, ± 1%, 62.5 mW, 0402 [1005 Metric], Thick Film, General Purpose"
			(at 0 0 270)
			(layer "F.Fab")
			(hide yes)
			(effects
				(font
					(size 1.27 1.27)
					(thickness 0.15)
				)
			)
		)
		(property "Author" "Antmicro"
			(at -31.71 276.71 0)
			(layer "F.Fab")
			(hide yes)
			(effects
				(font
					(size 1 1)
					(thickness 0.15)
				)
			)
		)
		(property "License" "Apache-2.0"
			(at -31.71 276.71 0)
			(layer "F.Fab")
			(hide yes)
			(effects
				(font
					(size 1 1)
					(thickness 0.15)
				)
			)
		)
		(property "MPN" "CR0402-FX-1002GLF"
			(at -31.71 276.71 0)
			(layer "F.Fab")
			(hide yes)
			(effects
				(font
					(size 1 1)
					(thickness 0.15)
				)
			)
		)
		(property "Manufacturer" "Bourns"
			(at -31.71 276.71 0)
			(layer "F.Fab")
			(hide yes)
			(effects
				(font
					(size 1 1)
					(thickness 0.15)
				)
			)
		)
		(property "Tolerance" "1%"
			(at -31.71 276.71 0)
			(layer "F.Fab")
			(hide yes)
			(effects
				(font
					(size 1 1)
					(thickness 0.15)
				)
			)
		)
		(property "Val" "10k"
			(at -31.71 276.71 0)
			(layer "F.Fab")
			(hide yes)
			(effects
				(font
					(size 1 1)
					(thickness 0.15)
				)
			)
		)
		(sheetname "/PCIe-connector/")
		(sheetfile "pcie-conn.kicad_sch")
		(attr smd)
		(fp_rect
			(start -0.925 -0.47)
			(end 0.925 0.47)
			(stroke
				(width 0.05)
				(type default)
			)
			(fill no)
			(layer "F.CrtYd")
		)
		(fp_rect
			(start -0.5 -0.25)
			(end 0.5 0.25)
			(stroke
				(width 0.15)
				(type solid)
			)
			(fill no)
			(layer "F.Fab")
		)
		(pad "1" smd roundrect
			(at -0.48 0 270)
			(size 0.59 0.64)
			(layers "F.Cu" "F.Mask" "F.Paste")
			(roundrect_rratio 0.25)
			(net 2 "VCC3V3")
			(pintype "passive")
		)
		(pad "2" smd roundrect
			(at 0.48 0 270)
			(size 0.59 0.64)
			(layers "F.Cu" "F.Mask" "F.Paste")
			(roundrect_rratio 0.25)
			(net 269 "Net-(J2-~{CLKREQ})")
			(pintype "passive")
		)
	)
	(footprint "antmicro-footprints:R_0402_1005Metric"
		(layer "F.Cu")
		(at 139.065 160.465)
		(descr "Resistor SMD 0402")
		(tags "resistor SMD 0402")
		(property "Reference" "R18"
			(at -1.065 1.335 0)
			(layer "F.SilkS")
			(effects
				(font
					(size 0.7 0.7)
					(thickness 0.15)
				)
				(justify left bottom)
			)
		)
		(property "Value" "R_330R_0402"
			(at 0 1.4 0)
			(layer "F.Fab")
			(effects
				(font
					(size 0.7 0.7)
					(thickness 0.15)
				)
				(justify left bottom)
			)
		)
		(property "Datasheet" "https://www.bourns.com/docs/product-datasheets/cr.pdf"
			(at 0 0 0)
			(layer "F.Fab")
			(hide yes)
			(effects
				(font
					(size 1.27 1.27)
					(thickness 0.15)
				)
			)
		)
		(property "Description" "SMD Chip Resistor, 330 ohm, ± 1%, 62.5 mW, 0402 [1005 Metric], Thick Film, General Purpose"
			(at 0 0 0)
			(layer "F.Fab")
			(hide yes)
			(effects
				(font
					(size 1.27 1.27)
					(thickness 0.15)
				)
			)
		)
		(property "Author" "Antmicro"
			(at 0 0 0)
			(layer "F.Fab")
			(hide yes)
			(effects
				(font
					(size 1 1)
					(thickness 0.15)
				)
			)
		)
		(property "License" "Apache-2.0"
			(at 0 0 0)
			(layer "F.Fab")
			(hide yes)
			(effects
				(font
					(size 1 1)
					(thickness 0.15)
				)
			)
		)
		(property "MPN" "CR0402-FX-3300GLF"
			(at 0 0 0)
			(layer "F.Fab")
			(hide yes)
			(effects
				(font
					(size 1 1)
					(thickness 0.15)
				)
			)
		)
		(property "Manufacturer" "Bourns"
			(at 0 0 0)
			(layer "F.Fab")
			(hide yes)
			(effects
				(font
					(size 1 1)
					(thickness 0.15)
				)
			)
		)
		(property "Tolerance" "1%"
			(at 0 0 0)
			(layer "F.Fab")
			(hide yes)
			(effects
				(font
					(size 1 1)
					(thickness 0.15)
				)
			)
		)
		(property "Val" "330R"
			(at 0 0 0)
			(layer "F.Fab")
			(hide yes)
			(effects
				(font
					(size 1 1)
					(thickness 0.15)
				)
			)
		)
		(sheetname "/PCIe-connector/")
		(sheetfile "pcie-conn.kicad_sch")
		(attr smd)
		(fp_rect
			(start -0.925 -0.47)
			(end 0.925 0.47)
			(stroke
				(width 0.05)
				(type default)
			)
			(fill no)
			(layer "F.CrtYd")
		)
		(fp_rect
			(start -0.5 -0.25)
			(end 0.5 0.25)
			(stroke
				(width 0.15)
				(type solid)
			)
			(fill no)
			(layer "F.Fab")
		)
		(pad "1" smd roundrect
			(at -0.48 0)
			(size 0.59 0.64)
			(layers "F.Cu" "F.Mask" "F.Paste")
			(roundrect_rratio 0.25)
			(net 112 "Net-(D1-A)")
			(pintype "passive")
		)
		(pad "2" smd roundrect
			(at 0.48 0)
			(size 0.59 0.64)
			(layers "F.Cu" "F.Mask" "F.Paste")
			(roundrect_rratio 0.25)
			(net 2 "VCC3V3")
			(pintype "passive")
		)
	)
	(footprint "antmicro-footprints:R_0402_1005Metric"
		(layer "F.Cu")
		(at 123.54 154.21 -90)
		(descr "Resistor SMD 0402")
		(tags "resistor SMD 0402")
		(property "Reference" "R19"
			(at -2.92 -0.33 90)
			(layer "F.SilkS")
			(effects
				(font
					(size 0.7 0.7)
					(thickness 0.15)
				)
				(justify right bottom)
			)
		)
		(property "Value" "R_10k_0402"
			(at 0 1.4 90)
			(layer "F.Fab")
			(effects
				(font
					(size 0.7 0.7)
					(thickness 0.15)
				)
				(justify right bottom)
			)
		)
		(property "Datasheet" "https://www.bourns.com/docs/product-datasheets/cr.pdf"
			(at 0 0 270)
			(layer "F.Fab")
			(hide yes)
			(effects
				(font
					(size 1.27 1.27)
					(thickness 0.15)
				)
			)
		)
		(property "Description" "SMD Chip Resistor, 10 kohm, ± 1%, 62.5 mW, 0402 [1005 Metric], Thick Film, General Purpose"
			(at 0 0 270)
			(layer "F.Fab")
			(hide yes)
			(effects
				(font
					(size 1.27 1.27)
					(thickness 0.15)
				)
			)
		)
		(property "Author" "Antmicro"
			(at -30.67 277.75 0)
			(layer "F.Fab")
			(hide yes)
			(effects
				(font
					(size 1 1)
					(thickness 0.15)
				)
			)
		)
		(property "License" "Apache-2.0"
			(at -30.67 277.75 0)
			(layer "F.Fab")
			(hide yes)
			(effects
				(font
					(size 1 1)
					(thickness 0.15)
				)
			)
		)
		(property "MPN" "CR0402-FX-1002GLF"
			(at -30.67 277.75 0)
			(layer "F.Fab")
			(hide yes)
			(effects
				(font
					(size 1 1)
					(thickness 0.15)
				)
			)
		)
		(property "Manufacturer" "Bourns"
			(at -30.67 277.75 0)
			(layer "F.Fab")
			(hide yes)
			(effects
				(font
					(size 1 1)
					(thickness 0.15)
				)
			)
		)
		(property "Tolerance" "1%"
			(at -30.67 277.75 0)
			(layer "F.Fab")
			(hide yes)
			(effects
				(font
					(size 1 1)
					(thickness 0.15)
				)
			)
		)
		(property "Val" "10k"
			(at -30.67 277.75 0)
			(layer "F.Fab")
			(hide yes)
			(effects
				(font
					(size 1 1)
					(thickness 0.15)
				)
			)
		)
		(sheetname "/PCIe-connector/")
		(sheetfile "pcie-conn.kicad_sch")
		(attr smd)
		(fp_rect
			(start -0.925 -0.47)
			(end 0.925 0.47)
			(stroke
				(width 0.05)
				(type default)
			)
			(fill no)
			(layer "F.CrtYd")
		)
		(fp_rect
			(start -0.5 -0.25)
			(end 0.5 0.25)
			(stroke
				(width 0.15)
				(type solid)
			)
			(fill no)
			(layer "F.Fab")
		)
		(pad "1" smd roundrect
			(at -0.48 0 270)
			(size 0.59 0.64)
			(layers "F.Cu" "F.Mask" "F.Paste")
			(roundrect_rratio 0.25)
			(net 2 "VCC3V3")
			(pintype "passive")
		)
		(pad "2" smd roundrect
			(at 0.48 0 270)
			(size 0.59 0.64)
			(layers "F.Cu" "F.Mask" "F.Paste")
			(roundrect_rratio 0.25)
			(net 118 "PRSNT1_N")
			(pintype "passive")
		)
	)
	(footprint "antmicro-footprints:C_0402_1005Metric"
		(layer "F.Cu")
		(at 99.375 161.875 90)
		(descr "Capacitor SMD 0402")
		(tags "capacitor SMD 0402")
		(property "Reference" "C40"
			(at -1.025 -0.675 90)
			(layer "F.SilkS")
			(effects
				(font
					(size 0.7 0.7)
					(thickness 0.15)
				)
				(justify left bottom)
			)
		)
		(property "Value" "C_10u_0402"
			(at 0 1.4 90)
			(layer "F.Fab")
			(effects
				(font
					(size 0.7 0.7)
					(thickness 0.15)
				)
				(justify left bottom)
			)
		)
		(property "Datasheet" "https://www.yageo.com/en/Chart/Download/pdf/CC0402MRX5R5BB106"
			(at 0 0 90)
			(layer "F.Fab")
			(hide yes)
			(effects
				(font
					(size 1.27 1.27)
					(thickness 0.15)
				)
			)
		)
		(property "Description" "SMD Multilayer Ceramic Capacitor, 10 µF, 6.3 V, 0402 [1005 Metric], ± 20%, X5R, CC Series"
			(at 0 0 90)
			(layer "F.Fab")
			(hide yes)
			(effects
				(font
					(size 1.27 1.27)
					(thickness 0.15)
				)
			)
		)
		(property "Author" "Antmicro"
			(at 261.25 62.5 0)
			(layer "F.Fab")
			(hide yes)
			(effects
				(font
					(size 1 1)
					(thickness 0.15)
				)
			)
		)
		(property "Dielectric" ""
			(at 261.25 62.5 0)
			(layer "F.Fab")
			(hide yes)
			(effects
				(font
					(size 1 1)
					(thickness 0.15)
				)
			)
		)
		(property "License" "Apache-2.0"
			(at 261.25 62.5 0)
			(layer "F.Fab")
			(hide yes)
			(effects
				(font
					(size 1 1)
					(thickness 0.15)
				)
			)
		)
		(property "MPN" "CC0402MRX5R5BB106"
			(at 261.25 62.5 0)
			(layer "F.Fab")
			(hide yes)
			(effects
				(font
					(size 1 1)
					(thickness 0.15)
				)
			)
		)
		(property "Manufacturer" "YAGEO"
			(at 261.25 62.5 0)
			(layer "F.Fab")
			(hide yes)
			(effects
				(font
					(size 1 1)
					(thickness 0.15)
				)
			)
		)
		(property "Val" "10u"
			(at 261.25 62.5 0)
			(layer "F.Fab")
			(hide yes)
			(effects
				(font
					(size 1 1)
					(thickness 0.15)
				)
			)
		)
		(property "Voltage" ""
			(at 261.25 62.5 0)
			(layer "F.Fab")
			(hide yes)
			(effects
				(font
					(size 1 1)
					(thickness 0.15)
				)
			)
		)
		(sheetname "/DDR3/")
		(sheetfile "ddr3.kicad_sch")
		(attr smd)
		(fp_rect
			(start -0.925 -0.47)
			(end 0.925 0.47)
			(stroke
				(width 0.05)
				(type default)
			)
			(fill no)
			(layer "F.CrtYd")
		)
		(fp_line
			(start 0.504 -0.25)
			(end 0.504 0.248)
			(stroke
				(width 0.15)
				(type solid)
			)
			(layer "F.Fab")
		)
		(fp_line
			(start -0.494 -0.25)
			(end 0.504 -0.25)
			(stroke
				(width 0.15)
				(type solid)
			)
			(layer "F.Fab")
		)
		(fp_line
			(start 0.504 0.248)
			(end -0.494 0.248)
			(stroke
				(width 0.15)
				(type solid)
			)
			(layer "F.Fab")
		)
		(fp_line
			(start -0.494 0.248)
			(end -0.494 -0.25)
			(stroke
				(width 0.15)
				(type solid)
			)
			(layer "F.Fab")
		)
		(pad "1" smd roundrect
			(at -0.48 0 90)
			(size 0.59 0.64)
			(layers "F.Cu" "F.Mask" "F.Paste")
			(roundrect_rratio 0.25)
			(net 1 "GND")
			(pintype "passive")
		)
		(pad "2" smd roundrect
			(at 0.48 0 90)
			(size 0.59 0.64)
			(layers "F.Cu" "F.Mask" "F.Paste")
			(roundrect_rratio 0.25)
			(net 143 "/DDR3/DDR3_VTT")
			(pintype "passive")
		)
	)
	(footprint "antmicro-footprints:C_0402_1005Metric"
		(layer "F.Cu")
		(at 98.3 159.8 90)
		(descr "Capacitor SMD 0402")
		(tags "capacitor SMD 0402")
		(property "Reference" "C41"
			(at -1.2 -1.6 90)
			(layer "F.SilkS")
			(effects
				(font
					(size 0.7 0.7)
					(thickness 0.15)
				)
				(justify left bottom)
			)
		)
		(property "Value" "C_10u_0402"
			(at 0 1.4 90)
			(layer "F.Fab")
			(effects
				(font
					(size 0.7 0.7)
					(thickness 0.15)
				)
				(justify left bottom)
			)
		)
		(property "Datasheet" "https://www.yageo.com/en/Chart/Download/pdf/CC0402MRX5R5BB106"
			(at 0 0 90)
			(layer "F.Fab")
			(hide yes)
			(effects
				(font
					(size 1.27 1.27)
					(thickness 0.15)
				)
			)
		)
		(property "Description" "SMD Multilayer Ceramic Capacitor, 10 µF, 6.3 V, 0402 [1005 Metric], ± 20%, X5R, CC Series"
			(at 0 0 90)
			(layer "F.Fab")
			(hide yes)
			(effects
				(font
					(size 1.27 1.27)
					(thickness 0.15)
				)
			)
		)
		(property "Author" "Antmicro"
			(at 258.1 61.5 0)
			(layer "F.Fab")
			(hide yes)
			(effects
				(font
					(size 1 1)
					(thickness 0.15)
				)
			)
		)
		(property "Dielectric" ""
			(at 258.1 61.5 0)
			(layer "F.Fab")
			(hide yes)
			(effects
				(font
					(size 1 1)
					(thickness 0.15)
				)
			)
		)
		(property "License" "Apache-2.0"
			(at 258.1 61.5 0)
			(layer "F.Fab")
			(hide yes)
			(effects
				(font
					(size 1 1)
					(thickness 0.15)
				)
			)
		)
		(property "MPN" "CC0402MRX5R5BB106"
			(at 258.1 61.5 0)
			(layer "F.Fab")
			(hide yes)
			(effects
				(font
					(size 1 1)
					(thickness 0.15)
				)
			)
		)
		(property "Manufacturer" "YAGEO"
			(at 258.1 61.5 0)
			(layer "F.Fab")
			(hide yes)
			(effects
				(font
					(size 1 1)
					(thickness 0.15)
				)
			)
		)
		(property "Val" "10u"
			(at 258.1 61.5 0)
			(layer "F.Fab")
			(hide yes)
			(effects
				(font
					(size 1 1)
					(thickness 0.15)
				)
			)
		)
		(property "Voltage" ""
			(at 258.1 61.5 0)
			(layer "F.Fab")
			(hide yes)
			(effects
				(font
					(size 1 1)
					(thickness 0.15)
				)
			)
		)
		(sheetname "/DDR3/")
		(sheetfile "ddr3.kicad_sch")
		(attr smd)
		(fp_rect
			(start -0.925 -0.47)
			(end 0.925 0.47)
			(stroke
				(width 0.05)
				(type default)
			)
			(fill no)
			(layer "F.CrtYd")
		)
		(fp_line
			(start 0.504 -0.25)
			(end 0.504 0.248)
			(stroke
				(width 0.15)
				(type solid)
			)
			(layer "F.Fab")
		)
		(fp_line
			(start -0.494 -0.25)
			(end 0.504 -0.25)
			(stroke
				(width 0.15)
				(type solid)
			)
			(layer "F.Fab")
		)
		(fp_line
			(start 0.504 0.248)
			(end -0.494 0.248)
			(stroke
				(width 0.15)
				(type solid)
			)
			(layer "F.Fab")
		)
		(fp_line
			(start -0.494 0.248)
			(end -0.494 -0.25)
			(stroke
				(width 0.15)
				(type solid)
			)
			(layer "F.Fab")
		)
		(pad "1" smd roundrect
			(at -0.48 0 90)
			(size 0.59 0.64)
			(layers "F.Cu" "F.Mask" "F.Paste")
			(roundrect_rratio 0.25)
			(net 1 "GND")
			(pintype "passive")
		)
		(pad "2" smd roundrect
			(at 0.48 0 90)
			(size 0.59 0.64)
			(layers "F.Cu" "F.Mask" "F.Paste")
			(roundrect_rratio 0.25)
			(net 143 "/DDR3/DDR3_VTT")
			(pintype "passive")
		)
	)
)
